# T6G (Grand Teton) — schematic netlist excerpt (pin names and nets, part order shuffled) for the footprints in the layout excerpt that follows; sources: Cadence DE-HDL packaged netlist, KiCad conversion of 04192023_DAF0TMB3IC0_F0TG_MB_C_brd_V02_OCP.brd

J110  CONN112_10137002101LF  CONN112_10137002-101LF IO  pkg HSD_F112D8_P2W1-2_RDH  page 120
  A1  = GPU_FPGA_EROT_RECOV_BUF_N
  A2  = GND
  A3  = GPU_HMC_PRSNT_N
  A4  = GND
  A5  = GPU_BASE_HMC_READY
  A6  = GND
  A7  = GPU_BASE_STBY_EN_BUF
  A8  = GND
  B1  = GND
  B2  = P5E_CPU1_P2_RX_BUF_DN<1>
  B3  = GND
  B4  = P5E_CPU1_P2_RX_BUF_DN<3>
  B5  = GND
  B6  = P5E_CPU1_P2_RX_BUF_DN<5>
  B7  = GND
  B8  = P5E_CPU1_P2_RX_BUF_DN<7>
  C1  = P5E_CPU1_P2_RX_BUF_DN<0>
  C2  = P5E_CPU1_P2_RX_BUF_DP<1>
  C3  = P5E_CPU1_P2_RX_BUF_DN<2>
  C4  = P5E_CPU1_P2_RX_BUF_DP<3>
  C5  = P5E_CPU1_P2_RX_BUF_DN<4>
  C6  = P5E_CPU1_P2_RX_BUF_DP<5>
  C7  = P5E_CPU1_P2_RX_BUF_DN<6>
  C8  = P5E_CPU1_P2_RX_BUF_DP<7>
  D1  = P5E_CPU1_P2_RX_BUF_DP<0>
  D2  = GND
  D3  = P5E_CPU1_P2_RX_BUF_DP<2>
  D4  = GND
  D5  = P5E_CPU1_P2_RX_BUF_DP<4>
  D6  = GND
  D7  = P5E_CPU1_P2_RX_BUF_DP<6>
  D8  = GND
  E1  = GND
  E2  = P5E_CPU1_P3_RX_BUF_DN<1>
  E3  = GND
  E4  = P5E_CPU1_P3_RX_BUF_DN<3>
  E5  = GND
  E6  = P5E_CPU1_P3_RX_BUF_DN<5>
  E7  = GND
  E8  = P5E_CPU1_P3_RX_BUF_DN<7>
  F1  = P5E_CPU1_P3_RX_BUF_DN<0>
  F2  = P5E_CPU1_P3_RX_BUF_DP<1>
  F3  = P5E_CPU1_P3_RX_BUF_DN<2>
  F4  = P5E_CPU1_P3_RX_BUF_DP<3>
  F5  = P5E_CPU1_P3_RX_BUF_DN<4>
  F6  = P5E_CPU1_P3_RX_BUF_DP<5>
  F7  = P5E_CPU1_P3_RX_BUF_DN<6>
  F8  = P5E_CPU1_P3_RX_BUF_DP<7>
  G1  = P5E_CPU1_P3_RX_BUF_DP<0>
  G2  = GND
  G3  = P5E_CPU1_P3_RX_BUF_DP<2>
  G4  = GND
  G5  = P5E_CPU1_P3_RX_BUF_DP<4>
  G6  = GND
  G7  = P5E_CPU1_P3_RX_BUF_DP<6>
  G8  = GND
  H1  = GND
  H2  = P5E_CPU1_P2_TX_BUF_C_DN<1>
  H3  = GND
  H4  = P5E_CPU1_P2_TX_BUF_C_DN<3>
  H5  = GND
  H6  = P5E_CPU1_P2_TX_BUF_C_DN<5>
  H7  = GND
  H8  = P5E_CPU1_P2_TX_BUF_C_DN<7>
  I1  = P5E_CPU1_P2_TX_BUF_C_DN<0>
  I2  = P5E_CPU1_P2_TX_BUF_C_DP<1>
  I3  = P5E_CPU1_P2_TX_BUF_C_DN<2>
  I4  = P5E_CPU1_P2_TX_BUF_C_DP<3>
  I5  = P5E_CPU1_P2_TX_BUF_C_DN<4>
  I6  = P5E_CPU1_P2_TX_BUF_C_DP<5>
  I7  = P5E_CPU1_P2_TX_BUF_C_DN<6>
  I8  = P5E_CPU1_P2_TX_BUF_C_DP<7>
  J1  = P5E_CPU1_P2_TX_BUF_C_DP<0>
  J2  = GND
  J3  = P5E_CPU1_P2_TX_BUF_C_DP<2>
  J4  = GND
  J5  = P5E_CPU1_P2_TX_BUF_C_DP<4>
  J6  = GND
  J7  = P5E_CPU1_P2_TX_BUF_C_DP<6>
  J8  = GND
  K1  = GND
  K2  = P5E_CPU1_P3_TX_BUF_C_DN<1>
  K3  = GND
  K4  = P5E_CPU1_P3_TX_BUF_C_DN<3>
  K5  = GND
  K6  = P5E_CPU1_P3_TX_BUF_C_DN<5>
  K7  = GND
  K8  = P5E_CPU1_P3_TX_BUF_C_DN<7>
  L1  = P5E_CPU1_P3_TX_BUF_C_DN<0>
  L2  = P5E_CPU1_P3_TX_BUF_C_DP<1>
  L3  = P5E_CPU1_P3_TX_BUF_C_DN<2>
  L4  = P5E_CPU1_P3_TX_BUF_C_DP<3>
  L5  = P5E_CPU1_P3_TX_BUF_C_DN<4>
  L6  = P5E_CPU1_P3_TX_BUF_C_DP<5>
  L7  = P5E_CPU1_P3_TX_BUF_C_DN<6>
  L8  = P5E_CPU1_P3_TX_BUF_C_DP<7>
  M1  = P5E_CPU1_P3_TX_BUF_C_DP<0>
  M2  = GND
  M3  = P5E_CPU1_P3_TX_BUF_C_DP<2>
  M4  = GND
  M5  = P5E_CPU1_P3_TX_BUF_C_DP<4>
  M6  = GND
  M7  = P5E_CPU1_P3_TX_BUF_C_DP<6>
  M8  = GND
  N1  = GND
  N2  = GPU_FPGA_BOOT_EN_BUF
  N3  = GND
  N4  = FM_SMB_1_ALERT_GPU_N
  N5  = GND
  N6  = FM_SMB_2_ALERT_GPU_N
  N7  = GND
  N8  = GPU_FPGA_EROT_RST_BUF_N

(kicad_pcb
	(version 20260206)
	(generator "pcbnew")
	(generator_version "10.0")
	(general
		(thickness 1.6)
		(legacy_teardrops no)
	)
	(paper "A4")
	(title_block
		(title "04192023_DAF0TMB3IC0_F0TG_MB_C_brd_V02_OCP.brd")
		(comment 1 "Grand Teton / footprint 3846 of 8354 (J110), pads 32-48 of 48")
	)
	(layers
		(0 "F.Cu" signal "TOP")
		(4 "In1.Cu" signal "GND")
		(6 "In2.Cu" signal "IN1")
		(8 "In3.Cu" signal "GND1")
		(10 "In4.Cu" signal "IN2")
		(12 "In5.Cu" signal "GND2")
		(14 "In6.Cu" signal "IN3")
		(16 "In7.Cu" signal "GND3")
		(18 "In8.Cu" signal "VCC")
		(20 "In9.Cu" signal "VCC1")
		(22 "In10.Cu" signal "GND4")
		(24 "In11.Cu" signal "IN4")
		(26 "In12.Cu" signal "GND5")
		(28 "In13.Cu" signal "IN5")
		(30 "In14.Cu" signal "GND6")
		(32 "In15.Cu" signal "IN6")
		(34 "In16.Cu" signal "GND7")
		(2 "B.Cu" signal "BOTTOM")
		(9 "F.Adhes" user "F.Adhesive")
		(11 "B.Adhes" user "B.Adhesive")
		(13 "F.Paste" user "Package Geometry/Pastemask Top")
		(15 "B.Paste" user "Package Geometry/Pastemask Bottom")
		(5 "F.SilkS" user "Ref Des/Silkscreen Top")
		(7 "B.SilkS" user "Ref Des/Silkscreen Bottom")
		(1 "F.Mask" user "Board Geometry/Soldermask Top")
		(3 "B.Mask" user "Board Geometry/Soldermask Bottom")
		(17 "Dwgs.User" user "User.Drawings")
		(19 "Cmts.User" user "User.Comments")
		(21 "Eco1.User" user "User.Eco1")
		(23 "Eco2.User" user "User.Eco2")
		(25 "Edge.Cuts" user "Board Geometry/Outline")
		(27 "Margin" user)
		(31 "F.CrtYd" user "Package Geometry/Place Bound Top")
		(29 "B.CrtYd" user "Package Geometry/Place Bound Bottom")
		(35 "F.Fab" user "Ref Des/Assembly Top")
		(33 "B.Fab" user "Ref Des/Assembly Bottom")
	)
	(footprint ""
		(layer "F.Cu")
		(at 125.749812 -440.489848)
		(property "Reference" "J110"
			(at -4.40944 23.347172 0)
			(unlocked yes)
			(layer "F.SilkS")
			(effects
				(font
					(size 0.7874 0.5842)
					(thickness 0.1524)
				)
				(justify left)
			)
		)
		(property "Value" ""
			(at 0 0 0)
			(layer "F.Fab")
			(effects
				(font
					(size 1.27 1.27)
				)
			)
		)
		(duplicate_pad_numbers_are_jumpers no)
		(pad "J8" thru_hole circle
			(at 13.999972 10.999978 180)
			(size 0.906272 0.906272)
			(drill 0.499872)
			(layers "*.Cu" "*.Mask")
			(remove_unused_layers no)
			(net "GND")
			(clearance 0.0508)
			(thermal_gap 0.0508)
		)
		(pad "K1" thru_hole circle
			(at 0 11.999976 180)
			(size 0.906272 0.906272)
			(drill 0.499872)
			(layers "*.Cu" "*.Mask")
			(remove_unused_layers no)
			(net "GND")
			(clearance 0.0508)
			(thermal_gap 0.0508)
		)
		(pad "K3" thru_hole circle
			(at 3.999992 11.999976 180)
			(size 0.906272 0.906272)
			(drill 0.499872)
			(layers "*.Cu" "*.Mask")
			(remove_unused_layers no)
			(net "GND")
			(clearance 0.0508)
			(thermal_gap 0.0508)
		)
		(pad "K5" thru_hole circle
			(at 7.999984 11.999976 180)
			(size 0.906272 0.906272)
			(drill 0.499872)
			(layers "*.Cu" "*.Mask")
			(remove_unused_layers no)
			(net "GND")
			(clearance 0.0508)
			(thermal_gap 0.0508)
		)
		(pad "K7" thru_hole circle
			(at 11.999976 11.999976 180)
			(size 0.906272 0.906272)
			(drill 0.499872)
			(layers "*.Cu" "*.Mask")
			(remove_unused_layers no)
			(net "GND")
			(clearance 0.0508)
			(thermal_gap 0.0508)
		)
		(pad "M2" thru_hole circle
			(at 1.999996 14.59992 180)
			(size 0.906272 0.906272)
			(drill 0.499872)
			(layers "*.Cu" "*.Mask")
			(remove_unused_layers no)
			(net "GND")
			(clearance 0.0508)
			(thermal_gap 0.0508)
		)
		(pad "M4" thru_hole circle
			(at 5.999988 14.59992 180)
			(size 0.906272 0.906272)
			(drill 0.499872)
			(layers "*.Cu" "*.Mask")
			(remove_unused_layers no)
			(net "GND")
			(clearance 0.0508)
			(thermal_gap 0.0508)
		)
		(pad "M6" thru_hole circle
			(at 9.99998 14.59992 180)
			(size 0.906272 0.906272)
			(drill 0.499872)
			(layers "*.Cu" "*.Mask")
			(remove_unused_layers no)
			(net "GND")
			(clearance 0.0508)
			(thermal_gap 0.0508)
		)
		(pad "M8" thru_hole circle
			(at 13.999972 14.59992 180)
			(size 0.906272 0.906272)
			(drill 0.499872)
			(layers "*.Cu" "*.Mask")
			(remove_unused_layers no)
			(net "GND")
			(clearance 0.0508)
			(thermal_gap 0.0508)
		)
		(pad "N1" thru_hole circle
			(at 0 15.599918 180)
			(size 0.906272 0.906272)
			(drill 0.499872)
			(layers "*.Cu" "*.Mask")
			(remove_unused_layers no)
			(net "GND")
			(clearance 0.0508)
			(thermal_gap 0.0508)
		)
		(pad "N2" thru_hole circle
			(at 1.999996 15.80007 180)
			(size 0.766318 0.766318)
			(drill 0.359918)
			(layers "*.Cu" "*.Mask")
			(remove_unused_layers no)
			(net "GPU_FPGA_BOOT_EN_BUF")
			(clearance 0.0508)
			(thermal_gap 0.0508)
		)
		(pad "N3" thru_hole circle
			(at 3.999992 15.599918 180)
			(size 0.906272 0.906272)
			(drill 0.499872)
			(layers "*.Cu" "*.Mask")
			(remove_unused_layers no)
			(net "GND")
			(clearance 0.0508)
			(thermal_gap 0.0508)
		)
		(pad "N4" thru_hole circle
			(at 5.999988 15.80007 180)
			(size 0.766318 0.766318)
			(drill 0.359918)
			(layers "*.Cu" "*.Mask")
			(remove_unused_layers no)
			(net "FM_SMB_1_ALERT_GPU_N")
			(clearance 0.0508)
			(thermal_gap 0.0508)
		)
		(pad "N5" thru_hole circle
			(at 7.999984 15.599918 180)
			(size 0.906272 0.906272)
			(drill 0.499872)
			(layers "*.Cu" "*.Mask")
			(remove_unused_layers no)
			(net "GND")
			(clearance 0.0508)
			(thermal_gap 0.0508)
		)
		(pad "N6" thru_hole circle
			(at 9.99998 15.80007 180)
			(size 0.766318 0.766318)
			(drill 0.359918)
			(layers "*.Cu" "*.Mask")
			(remove_unused_layers no)
			(net "FM_SMB_2_ALERT_GPU_N")
			(clearance 0.0508)
			(thermal_gap 0.0508)
		)
		(pad "N7" thru_hole circle
			(at 11.999976 15.599918 180)
			(size 0.906272 0.906272)
			(drill 0.499872)
			(layers "*.Cu" "*.Mask")
			(remove_unused_layers no)
			(net "GND")
			(clearance 0.0508)
			(thermal_gap 0.0508)
		)
		(pad "N8" thru_hole circle
			(at 13.999972 15.80007 180)
			(size 0.766318 0.766318)
			(drill 0.359918)
			(layers "*.Cu" "*.Mask")
			(remove_unused_layers no)
			(net "GPU_FPGA_EROT_RST_BUF_N")
			(clearance 0.0508)
			(thermal_gap 0.0508)
		)
	)
)
